(kicad_pcb
	(version 20241229)
	(generator "pcbnew")
	(generator_version "9.0")
	(general
		(thickness 1.711)
		(legacy_teardrops no)
	)
	(paper "A4")
	(title_block
		(title "Antmicro Baseboard for Jetson AGX Thor")
		(date "2026-02-18")
		(rev "1.1.0")
		(company "Antmicro Ltd")
		(comment 1 "www.antmicro.com")
		(comment 9 "footprints 548-551 of 1170")
	)
	(layers
		(0 "F.Cu" signal)
		(4 "In1.Cu" signal)
		(6 "In2.Cu" signal)
		(8 "In3.Cu" signal)
		(10 "In4.Cu" jumper)
		(12 "In5.Cu" signal)
		(14 "In6.Cu" signal)
		(16 "In7.Cu" signal)
		(18 "In8.Cu" signal)
		(2 "B.Cu" signal)
		(9 "F.Adhes" user "F.Adhesive")
		(11 "B.Adhes" user "B.Adhesive")
		(13 "F.Paste" user)
		(15 "B.Paste" user)
		(5 "F.SilkS" user "F.Silkscreen")
		(7 "B.SilkS" user "B.Silkscreen")
		(1 "F.Mask" user)
		(3 "B.Mask" user)
		(17 "Dwgs.User" user "User.Drawings")
		(19 "Cmts.User" user "User.Comments")
		(21 "Eco1.User" user "User.Eco1")
		(23 "Eco2.User" user "User.Eco2")
		(25 "Edge.Cuts" user)
		(27 "Margin" user)
		(31 "F.CrtYd" user "F.Courtyard")
		(29 "B.CrtYd" user "B.Courtyard")
		(35 "F.Fab" user)
		(33 "B.Fab" user)
	)
	(footprint "antmicro-footprints:DFN-6-1EP_3x3mm_P1mm_EP1.5x2.4mm"
		(layer "F.Cu")
		(at 138.6 57.3)
		(descr "DFN, 6 Pin")
		(tags "DFN NoLead")
		(property "Reference" "U79"
			(at -1.01 -1.8 0)
			(layer "F.SilkS")
			(effects
				(font
					(size 0.7 0.7)
					(thickness 0.15)
				)
				(justify left bottom)
			)
		)
		(property "Value" "LD39100PUR"
			(at 0 2.600001 0)
			(layer "F.Fab")
			(effects
				(font
					(size 0.7 0.7)
					(thickness 0.15)
				)
				(justify left bottom)
			)
		)
		(property "Datasheet" "https://eu.mouser.com/datasheet/2/389/ld39100-1849679.pdf"
			(at 0 0 0)
			(layer "F.Fab")
			(hide yes)
			(effects
				(font
					(size 1.27 1.27)
					(thickness 0.15)
				)
			)
		)
		(property "Description" "LDO Voltage Regulator 1A Low Quiescent Reg 1.5 to 5.5 V 200mV"
			(at 0 0 0)
			(layer "F.Fab")
			(hide yes)
			(effects
				(font
					(size 1.27 1.27)
					(thickness 0.15)
				)
			)
		)
		(property "MPN" "LD39100PUR"
			(at 0 0 0)
			(unlocked yes)
			(layer "F.Fab")
			(hide yes)
			(effects
				(font
					(size 1 1)
					(thickness 0.15)
				)
			)
		)
		(property "Manufacturer" "STMicroelectronics"
			(at 0 0 0)
			(unlocked yes)
			(layer "F.Fab")
			(hide yes)
			(effects
				(font
					(size 1 1)
					(thickness 0.15)
				)
			)
		)
		(property "Author" "Antmicro"
			(at 0 0 0)
			(unlocked yes)
			(layer "F.Fab")
			(hide yes)
			(effects
				(font
					(size 1 1)
					(thickness 0.15)
				)
			)
		)
		(property "License" "Apache-2.0"
			(at 0 0 0)
			(unlocked yes)
			(layer "F.Fab")
			(hide yes)
			(effects
				(font
					(size 1 1)
					(thickness 0.15)
				)
			)
		)
		(sheetname "/Power/")
		(sheetfile "power.kicad_sch")
		(attr smd)
		(fp_line
			(start -1.5 -1.6)
			(end 1.5 -1.6)
			(stroke
				(width 0.15)
				(type solid)
			)
			(layer "F.SilkS")
		)
		(fp_line
			(start -1.5 1.61)
			(end 1.499 1.61)
			(stroke
				(width 0.15)
				(type solid)
			)
			(layer "F.SilkS")
		)
		(fp_circle
			(center -1.7 -1.4)
			(end -1.65 -1.4)
			(stroke
				(width 0.15)
				(type solid)
			)
			(fill yes)
			(layer "F.SilkS")
		)
		(fp_poly
			(pts
				(xy -1.899999 -1.7) (xy 1.899999 -1.7) (xy 1.899999 1.7) (xy -1.899999 1.7)
			)
			(stroke
				(width 0.05)
				(type solid)
			)
			(fill no)
			(layer "F.CrtYd")
		)
		(fp_line
			(start -1.5 -0.75)
			(end -0.75 -1.5)
			(stroke
				(width 0.15)
				(type solid)
			)
			(layer "F.Fab")
		)
		(fp_line
			(start -1.5 1.499)
			(end -1.5 -0.75)
			(stroke
				(width 0.15)
				(type solid)
			)
			(layer "F.Fab")
		)
		(fp_line
			(start -0.75 -1.5)
			(end 1.499 -1.5)
			(stroke
				(width 0.15)
				(type solid)
			)
			(layer "F.Fab")
		)
		(fp_line
			(start 1.499 -1.5)
			(end 1.499 1.499)
			(stroke
				(width 0.15)
				(type solid)
			)
			(layer "F.Fab")
		)
		(fp_line
			(start 1.499 1.499)
			(end -1.5 1.499)
			(stroke
				(width 0.15)
				(type solid)
			)
			(layer "F.Fab")
		)
		(fp_text user "License: Apache-2.0"
			(at -2.101 6.85 0)
			(layer "F.Fab")
			(effects
				(font
					(size 0.7 0.7)
					(thickness 0.15)
				)
				(justify left bottom)
			)
		)
		(fp_text user "${REFERENCE}"
			(at -2.101 4.45 0)
			(layer "F.Fab")
			(effects
				(font
					(size 0.7 0.7)
					(thickness 0.15)
				)
				(justify left bottom)
			)
		)
		(fp_text user "Author: Antmicro"
			(at -2.101 5.65 0)
			(layer "F.Fab")
			(effects
				(font
					(size 0.7 0.7)
					(thickness 0.15)
				)
				(justify left bottom)
			)
		)
		(pad "" smd roundrect
			(at -0.375 -0.6)
			(size 0.6 0.97)
			(layers "F.Paste")
			(roundrect_rratio 0.25)
		)
		(pad "" smd roundrect
			(at -0.375 0.598)
			(size 0.6 0.97)
			(layers "F.Paste")
			(roundrect_rratio 0.25)
		)
		(pad "" smd roundrect
			(at 0.373 -0.6)
			(size 0.6 0.97)
			(layers "F.Paste")
			(roundrect_rratio 0.25)
		)
		(pad "" smd roundrect
			(at 0.373 0.598)
			(size 0.6 0.97)
			(layers "F.Paste")
			(roundrect_rratio 0.25)
		)
		(pad "1" smd roundrect
			(at -1.45 -1)
			(size 0.8 0.4)
			(layers "F.Cu" "F.Mask" "F.Paste")
			(roundrect_rratio 0.25)
			(net 491 "+5V_AON")
			(pinfunction "EN")
			(pintype "input")
		)
		(pad "2" smd roundrect
			(at -1.45 0)
			(size 0.8 0.4)
			(layers "F.Cu" "F.Mask" "F.Paste")
			(roundrect_rratio 0.25)
			(net 1 "GND")
			(pinfunction "GND")
			(pintype "power_in")
		)
		(pad "3" smd roundrect
			(at -1.45 0.998)
			(size 0.8 0.4)
			(layers "F.Cu" "F.Mask" "F.Paste")
			(roundrect_rratio 0.25)
			(net 1397 "unconnected-(U79-PG-Pad3)")
			(pinfunction "PG")
			(pintype "open_collector+no_connect")
		)
		(pad "4" smd roundrect
			(at 1.449 0.998)
			(size 0.8 0.4)
			(layers "F.Cu" "F.Mask" "F.Paste")
			(roundrect_rratio 0.25)
			(net 31 "/Power/3V3_LDO")
			(pinfunction "V_{OUT}")
			(pintype "power_out")
		)
		(pad "5" smd roundrect
			(at 1.449 0)
			(size 0.8 0.4)
			(layers "F.Cu" "F.Mask" "F.Paste")
			(roundrect_rratio 0.25)
			(net 1396 "Net-(U79-ADJ)")
			(pinfunction "ADJ")
			(pintype "input")
		)
		(pad "6" smd roundrect
			(at 1.449 -1)
			(size 0.8 0.4)
			(layers "F.Cu" "F.Mask" "F.Paste")
			(roundrect_rratio 0.25)
			(net 491 "+5V_AON")
			(pinfunction "V_{IN}")
			(pintype "power_in")
		)
		(pad "7" smd rect
			(at 0 0)
			(size 1.5 2.4)
			(layers "F.Cu" "F.Mask")
			(net 1 "GND")
			(pinfunction "GND")
			(pintype "passive")
		)
	)
	(footprint "antmicro-footprints:R_0402_1005Metric"
		(layer "F.Cu")
		(at 232.540532 95.71 180)
		(descr "Resistor SMD 0402")
		(tags "resistor SMD 0402")
		(property "Reference" "R157"
			(at -1.122484 -0.772697 0)
			(layer "F.SilkS")
			(effects
				(font
					(size 0.7 0.7)
					(thickness 0.15)
				)
				(justify right top)
			)
		)
		(property "Value" "R_4k7_0402"
			(at -1.011843 1.772046 0)
			(layer "F.Fab")
			(effects
				(font
					(size 0.7 0.7)
					(thickness 0.15)
				)
				(justify right top)
			)
		)
		(property "Datasheet" "https://www.bourns.com/docs/product-datasheets/cr.pdf"
			(at 0 0 0)
			(layer "F.Fab")
			(hide yes)
			(effects
				(font
					(size 1.27 1.27)
					(thickness 0.15)
				)
			)
		)
		(property "Description" "SMD Chip Resistor, 4.7 kohm, ± 1%, 62.5 mW, 0402 [1005 Metric], Thick Film, General Purpose"
			(at 0 0 0)
			(layer "F.Fab")
			(hide yes)
			(effects
				(font
					(size 1.27 1.27)
					(thickness 0.15)
				)
			)
		)
		(property "Manufacturer" "Bourns"
			(at 0 0 180)
			(unlocked yes)
			(layer "F.Fab")
			(hide yes)
			(effects
				(font
					(size 1 1)
					(thickness 0.15)
				)
			)
		)
		(property "MPN" "CR0402-FX-4701GLF"
			(at 0 0 180)
			(unlocked yes)
			(layer "F.Fab")
			(hide yes)
			(effects
				(font
					(size 1 1)
					(thickness 0.15)
				)
			)
		)
		(property "Val" "4k7"
			(at 0 0 180)
			(unlocked yes)
			(layer "F.Fab")
			(hide yes)
			(effects
				(font
					(size 1 1)
					(thickness 0.15)
				)
			)
		)
		(property "License" "Apache-2.0"
			(at 0 0 180)
			(unlocked yes)
			(layer "F.Fab")
			(hide yes)
			(effects
				(font
					(size 1 1)
					(thickness 0.15)
				)
			)
		)
		(property "Author" "Antmicro"
			(at 0 0 180)
			(unlocked yes)
			(layer "F.Fab")
			(hide yes)
			(effects
				(font
					(size 1 1)
					(thickness 0.15)
				)
			)
		)
		(property "Tolerance" "1%"
			(at 0 0 180)
			(unlocked yes)
			(layer "F.Fab")
			(hide yes)
			(effects
				(font
					(size 1 1)
					(thickness 0.15)
				)
			)
		)
		(sheetname "/USB DP Alt mode/")
		(sheetfile "usb_dp.kicad_sch")
		(attr smd)
		(fp_poly
			(pts
				(xy -0.925 -0.47) (xy 0.925 -0.47) (xy 0.925 0.47) (xy -0.925 0.47)
			)
			(stroke
				(width 0.05)
				(type default)
			)
			(fill no)
			(layer "F.CrtYd")
		)
		(fp_poly
			(pts
				(xy -0.5 -0.25) (xy 0.5 -0.25) (xy 0.5 0.25) (xy -0.5 0.25)
			)
			(stroke
				(width 0.15)
				(type solid)
			)
			(fill no)
			(layer "F.Fab")
		)
		(fp_text user "${REFERENCE}"
			(at -0.95 3.168 0)
			(layer "F.Fab")
			(effects
				(font
					(size 0.7 0.7)
					(thickness 0.15)
				)
				(justify right top)
			)
		)
		(fp_text user "License: Apache-2.0"
			(at -0.949999 5.169 0)
			(layer "F.Fab")
			(effects
				(font
					(size 0.7 0.7)
					(thickness 0.15)
				)
				(justify right top)
			)
		)
		(fp_text user "Author: Antmicro"
			(at -0.95 4.169 0)
			(layer "F.Fab")
			(effects
				(font
					(size 0.7 0.7)
					(thickness 0.15)
				)
				(justify right top)
			)
		)
		(pad "1" smd roundrect
			(at -0.48 0 180)
			(size 0.59 0.64)
			(layers "F.Cu" "F.Mask" "F.Paste")
			(roundrect_rratio 0.25)
			(net 1388 "Net-(D25-A)")
			(pintype "passive")
		)
		(pad "2" smd roundrect
			(at 0.48 0 180)
			(size 0.59 0.64)
			(layers "F.Cu" "F.Mask" "F.Paste")
			(roundrect_rratio 0.25)
			(net 376 "/USB DP Alt mode/USBC1_VBUS")
			(pintype "passive")
		)
	)
	(footprint "antmicro-footprints:USON-8_2x3mm_P0.5mm"
		(layer "F.Cu")
		(at 192.95 84.45)
		(property "Reference" "U29"
			(at 1.011 1.710001 0)
			(layer "F.SilkS")
			(effects
				(font
					(size 0.7 0.7)
					(thickness 0.15)
				)
				(justify right top)
			)
		)
		(property "Value" "W25Q80DV_USON"
			(at 0 2.300001 0)
			(layer "F.Fab")
			(effects
				(font
					(size 0.7 0.7)
					(thickness 0.15)
				)
				(justify left bottom)
			)
		)
		(property "Datasheet" "https://www.mouser.com/datasheet/2/949/w25q80dv_dl_revh_10022015-1489677.pdf"
			(at 0 0 0)
			(layer "F.Fab")
			(hide yes)
			(effects
				(font
					(size 1.27 1.27)
					(thickness 0.15)
				)
			)
		)
		(property "Description" "FLASH - NOR Memory IC 8Mbit SPI - Quad I/O 104 MHz 8-USON (2x3)"
			(at 0 0 0)
			(layer "F.Fab")
			(hide yes)
			(effects
				(font
					(size 1.27 1.27)
					(thickness 0.15)
				)
			)
		)
		(property "MPN" "W25Q80DVUXIE TR"
			(at 0 0 0)
			(unlocked yes)
			(layer "F.Fab")
			(hide yes)
			(effects
				(font
					(size 1 1)
					(thickness 0.15)
				)
			)
		)
		(property "Manufacturer" "Winbond"
			(at 0 0 0)
			(unlocked yes)
			(layer "F.Fab")
			(hide yes)
			(effects
				(font
					(size 1 1)
					(thickness 0.15)
				)
			)
		)
		(property "Author" "Antmicro"
			(at 0 0 0)
			(unlocked yes)
			(layer "F.Fab")
			(hide yes)
			(effects
				(font
					(size 1 1)
					(thickness 0.15)
				)
			)
		)
		(property "License" "Apache-2.0"
			(at 0 0 0)
			(unlocked yes)
			(layer "F.Fab")
			(hide yes)
			(effects
				(font
					(size 1 1)
					(thickness 0.15)
				)
			)
		)
		(sheetname "/USB Debug, PD/")
		(sheetfile "usb_debug_pd.kicad_sch")
		(attr smd)
		(fp_line
			(start -1.710001 -0.89)
			(end -1.3 -1.301)
			(stroke
				(width 0.15)
				(type solid)
			)
			(layer "F.SilkS")
		)
		(fp_line
			(start -1.71 1.3)
			(end -1.710001 -0.89)
			(stroke
				(width 0.15)
				(type solid)
			)
			(layer "F.SilkS")
		)
		(fp_line
			(start -1.3 -1.301)
			(end 1.71 -1.3005)
			(stroke
				(width 0.15)
				(type solid)
			)
			(layer "F.SilkS")
		)
		(fp_line
			(start 1.71 -1.3005)
			(end 1.71 1.3005)
			(stroke
				(width 0.15)
				(type solid)
			)
			(layer "F.SilkS")
		)
		(fp_line
			(start 1.71 1.3005)
			(end -1.71 1.3)
			(stroke
				(width 0.15)
				(type solid)
			)
			(layer "F.SilkS")
		)
		(fp_circle
			(center -1.749999 -1.25)
			(end -1.7 -1.25)
			(stroke
				(width 0.15)
				(type solid)
			)
			(fill yes)
			(layer "F.SilkS")
		)
		(fp_poly
			(pts
				(xy 1.899999 -1.4) (xy -1.899999 -1.4) (xy -1.899999 1.4) (xy 1.899999 1.4)
			)
			(stroke
				(width 0.05)
				(type solid)
			)
			(fill no)
			(layer "F.CrtYd")
		)
		(fp_line
			(start -1.499 -0.499999)
			(end -0.998 -1)
			(stroke
				(width 0.15)
				(type solid)
			)
			(layer "F.Fab")
		)
		(fp_poly
			(pts
				(xy 1.5 1) (xy -1.5 1) (xy -1.5 -1) (xy 1.5 -1)
			)
			(stroke
				(width 0.15)
				(type solid)
			)
			(fill no)
			(layer "F.Fab")
		)
		(fp_text user "Author: Antmicro"
			(at -1.9 6.099 0)
			(layer "F.Fab")
			(effects
				(font
					(size 0.7 0.7)
					(thickness 0.15)
				)
				(justify left bottom)
			)
		)
		(fp_text user "${REFERENCE}"
			(at -1.899999 5.099 0)
			(layer "F.Fab")
			(effects
				(font
					(size 0.7 0.7)
					(thickness 0.15)
				)
				(justify left bottom)
			)
		)
		(fp_text user "License: Apache-2.0"
			(at -1.9 7.099 0)
			(layer "F.Fab")
			(effects
				(font
					(size 0.7 0.7)
					(thickness 0.15)
				)
				(justify left bottom)
			)
		)
		(pad "1" smd roundrect
			(at -1.273 -0.75 270)
			(size 0.3 0.7)
			(layers "F.Cu" "F.Mask" "F.Paste")
			(roundrect_rratio 0.25)
			(net 939 "/USB Debug, PD/~{PDC_CS}")
			(pinfunction "~{CS}")
			(pintype "input")
		)
		(pad "2" smd roundrect
			(at -1.273 -0.25 270)
			(size 0.3 0.7)
			(layers "F.Cu" "F.Mask" "F.Paste")
			(roundrect_rratio 0.25)
			(net 936 "/USB Debug, PD/PDC_MISO")
			(pinfunction "SO/IO1")
			(pintype "input")
		)
		(pad "3" smd roundrect
			(at -1.272999 0.248 270)
			(size 0.3 0.7)
			(layers "F.Cu" "F.Mask" "F.Paste")
			(roundrect_rratio 0.25)
			(net 271 "FLASH_PWR")
			(pinfunction "~{WP}/IO2")
			(pintype "input")
		)
		(pad "4" smd roundrect
			(at -1.273 0.748 270)
			(size 0.3 0.7)
			(layers "F.Cu" "F.Mask" "F.Paste")
			(roundrect_rratio 0.25)
			(net 1 "GND")
			(pinfunction "VSS")
			(pintype "power_in")
		)
		(pad "5" smd roundrect
			(at 1.276 0.748 270)
			(size 0.3 0.7)
			(layers "F.Cu" "F.Mask" "F.Paste")
			(roundrect_rratio 0.25)
			(net 940 "/USB Debug, PD/PDC_MOSI")
			(pinfunction "SI/IO0")
			(pintype "input")
		)
		(pad "6" smd roundrect
			(at 1.276 0.248 270)
			(size 0.3 0.7)
			(layers "F.Cu" "F.Mask" "F.Paste")
			(roundrect_rratio 0.25)
			(net 941 "/USB Debug, PD/PDC_SCLK")
			(pinfunction "SCLK")
			(pintype "input")
		)
		(pad "7" smd roundrect
			(at 1.276 -0.25 270)
			(size 0.3 0.7)
			(layers "F.Cu" "F.Mask" "F.Paste")
			(roundrect_rratio 0.25)
			(net 271 "FLASH_PWR")
			(pinfunction "~{HOLD}/IO3")
			(pintype "input")
		)
		(pad "8" smd roundrect
			(at 1.276 -0.75 270)
			(size 0.3 0.7)
			(layers "F.Cu" "F.Mask" "F.Paste")
			(roundrect_rratio 0.25)
			(net 271 "FLASH_PWR")
			(pinfunction "VCC")
			(pintype "power_in")
		)
		(pad "EP" smd roundrect
			(at 0 0)
			(size 0.2 1.6)
			(layers "F.Cu" "F.Mask" "F.Paste")
			(roundrect_rratio 0.25)
			(net 1107 "unconnected-(U29-PadEP)")
			(pinfunction "EP")
			(pintype "power_in+no_connect")
		)
	)
	(footprint "antmicro-footprints:R_0402_1005Metric"
		(layer "F.Cu")
		(at 193.026 149.7 180)
		(descr "Resistor SMD 0402")
		(tags "resistor SMD 0402")
		(property "Reference" "R204"
			(at -1.574 -0.9 0)
			(layer "F.SilkS")
			(effects
				(font
					(size 0.7 0.7)
					(thickness 0.15)
				)
				(justify right top)
			)
		)
		(property "Value" "R_200R_0402"
			(at -1.011843 1.772046 0)
			(layer "F.Fab")
			(effects
				(font
					(size 0.7 0.7)
					(thickness 0.15)
				)
				(justify right top)
			)
		)
		(property "Datasheet" "https://www.bourns.com/docs/product-datasheets/cr.pdf"
			(at 0 0 0)
			(layer "F.Fab")
			(hide yes)
			(effects
				(font
					(size 1.27 1.27)
					(thickness 0.15)
				)
			)
		)
		(property "Description" "SMD Chip Resistor, 200 ohm, ± 1%, 62.5 mW, 0402 [1005 Metric], Thick Film, General Purpose"
			(at 0 0 0)
			(layer "F.Fab")
			(hide yes)
			(effects
				(font
					(size 1.27 1.27)
					(thickness 0.15)
				)
			)
		)
		(property "MPN" "CR0402-FX-2000GLF"
			(at 0 0 180)
			(unlocked yes)
			(layer "F.Fab")
			(hide yes)
			(effects
				(font
					(size 1 1)
					(thickness 0.15)
				)
			)
		)
		(property "Manufacturer" "Bourns"
			(at 0 0 180)
			(unlocked yes)
			(layer "F.Fab")
			(hide yes)
			(effects
				(font
					(size 1 1)
					(thickness 0.15)
				)
			)
		)
		(property "License" "Apache-2.0"
			(at 0 0 180)
			(unlocked yes)
			(layer "F.Fab")
			(hide yes)
			(effects
				(font
					(size 1 1)
					(thickness 0.15)
				)
			)
		)
		(property "Author" "Antmicro"
			(at 0 0 180)
			(unlocked yes)
			(layer "F.Fab")
			(hide yes)
			(effects
				(font
					(size 1 1)
					(thickness 0.15)
				)
			)
		)
		(property "Val" "200R"
			(at 0 0 180)
			(unlocked yes)
			(layer "F.Fab")
			(hide yes)
			(effects
				(font
					(size 1 1)
					(thickness 0.15)
				)
			)
		)
		(property "Tolerance" "1%"
			(at 0 0 180)
			(unlocked yes)
			(layer "F.Fab")
			(hide yes)
			(effects
				(font
					(size 1 1)
					(thickness 0.15)
				)
			)
		)
		(sheetname "/SFP/")
		(sheetfile "sfp.kicad_sch")
		(attr smd)
		(fp_poly
			(pts
				(xy -0.925 -0.47) (xy 0.925 -0.47) (xy 0.925 0.47) (xy -0.925 0.47)
			)
			(stroke
				(width 0.05)
				(type default)
			)
			(fill no)
			(layer "F.CrtYd")
		)
		(fp_poly
			(pts
				(xy -0.5 -0.25) (xy 0.5 -0.25) (xy 0.5 0.25) (xy -0.5 0.25)
			)
			(stroke
				(width 0.15)
				(type solid)
			)
			(fill no)
			(layer "F.Fab")
		)
		(fp_text user "Author: Antmicro"
			(at -0.95 4.169 0)
			(layer "F.Fab")
			(effects
				(font
					(size 0.7 0.7)
					(thickness 0.15)
				)
				(justify right top)
			)
		)
		(fp_text user "${REFERENCE}"
			(at -0.95 3.168 0)
			(layer "F.Fab")
			(effects
				(font
					(size 0.7 0.7)
					(thickness 0.15)
				)
				(justify right top)
			)
		)
		(fp_text user "License: Apache-2.0"
			(at -0.949999 5.169 0)
			(layer "F.Fab")
			(effects
				(font
					(size 0.7 0.7)
					(thickness 0.15)
				)
				(justify right top)
			)
		)
		(pad "1" smd roundrect
			(at -0.48 0 180)
			(size 0.59 0.64)
			(layers "F.Cu" "F.Mask" "F.Paste")
			(roundrect_rratio 0.25)
			(net 1003 "/SFP/SFP_LEDY")
			(pintype "passive")
		)
		(pad "2" smd roundrect
			(at 0.48 0 180)
			(size 0.59 0.64)
			(layers "F.Cu" "F.Mask" "F.Paste")
			(roundrect_rratio 0.25)
			(net 543 "Net-(D30-C)")
			(pintype "passive")
		)
	)
)
